(kicad_pcb
	(version 20240108)
	(generator "pcbnew")
	(generator_version "8.0")
	(general
		(thickness 1.586)
		(legacy_teardrops no)
	)
	(paper "A4")
	(title_block
		(title "GMSL Serializer")
		(date "2024-11-27")
		(rev "1.1.1")
		(company "Antmicro Ltd")
		(comment 1 "www.antmicro.com")
		(comment 9 "footprints 110-113 of 117")
	)
	(layers
		(0 "F.Cu" signal)
		(1 "In1.Cu" power)
		(2 "In2.Cu" power)
		(31 "B.Cu" signal)
		(32 "B.Adhes" user "B.Adhesive")
		(33 "F.Adhes" user "F.Adhesive")
		(34 "B.Paste" user)
		(35 "F.Paste" user)
		(36 "B.SilkS" user "B.Silkscreen")
		(37 "F.SilkS" user "F.Silkscreen")
		(38 "B.Mask" user)
		(39 "F.Mask" user)
		(40 "Dwgs.User" user "User.Drawings")
		(41 "Cmts.User" user "User.Comments")
		(42 "Eco1.User" user "User.Eco1")
		(43 "Eco2.User" user "User.Eco2")
		(44 "Edge.Cuts" user)
		(45 "Margin" user)
		(46 "B.CrtYd" user "B.Courtyard")
		(47 "F.CrtYd" user "F.Courtyard")
		(48 "B.Fab" user)
		(49 "F.Fab" user)
	)
	(footprint "antmicro-footprints:LED_0603_1608Metric_G"
		(layer "F.Cu")
		(at 150.5 115.75 -90)
		(descr "LED SMD 0603 Green")
		(tags "LED SMD 0603 Green")
		(property "Reference" "D6"
			(at 0.325 -1.525 90)
			(layer "F.SilkS")
			(effects
				(font
					(size 0.7 0.7)
					(thickness 0.15)
				)
				(justify right bottom)
			)
		)
		(property "Value" "LED_G_0603_LTST-C190GKT"
			(at -0.001 1.599 90)
			(layer "F.Fab")
			(effects
				(font
					(size 0.7 0.7)
					(thickness 0.15)
				)
				(justify right bottom)
			)
		)
		(property "Footprint" "antmicro-footprints:LED_0603_1608Metric_G"
			(at 0 0 -90)
			(layer "F.Fab")
			(hide yes)
			(effects
				(font
					(size 1.27 1.27)
					(thickness 0.15)
				)
			)
		)
		(property "Datasheet" "https://media.digikey.com/pdf/Data%20Sheets/Lite-On%20PDFs/LTST-C190GKT.pdf"
			(at 0 0 -90)
			(layer "F.Fab")
			(hide yes)
			(effects
				(font
					(size 1.27 1.27)
					(thickness 0.15)
				)
			)
		)
		(property "Author" "Antmicro"
			(at 34.75 266.25 0)
			(layer "F.Fab")
			(hide yes)
			(effects
				(font
					(size 1 1)
					(thickness 0.15)
				)
			)
		)
		(property "Color" "Green"
			(at 34.75 266.25 0)
			(layer "F.Fab")
			(hide yes)
			(effects
				(font
					(size 1 1)
					(thickness 0.15)
				)
			)
		)
		(property "License" "Apache-2.0"
			(at 34.75 266.25 0)
			(layer "F.Fab")
			(hide yes)
			(effects
				(font
					(size 1 1)
					(thickness 0.15)
				)
			)
		)
		(property "MPN" "LTST-C190GKT"
			(at 34.75 266.25 0)
			(layer "F.Fab")
			(hide yes)
			(effects
				(font
					(size 1 1)
					(thickness 0.15)
				)
			)
		)
		(property "Manufacturer" "Lite-On"
			(at 34.75 266.25 0)
			(layer "F.Fab")
			(hide yes)
			(effects
				(font
					(size 1 1)
					(thickness 0.15)
				)
			)
		)
		(property "VSD_class" "LED"
			(at 34.75 266.25 0)
			(layer "F.Fab")
			(hide yes)
			(effects
				(font
					(size 1 1)
					(thickness 0.15)
				)
			)
		)
		(sheetname "Supply")
		(sheetfile "supply.kicad_sch")
		(attr smd)
		(fp_line
			(start 0.22 0.35)
			(end -0.22 0.35)
			(stroke
				(width 0.15)
				(type solid)
			)
			(layer "F.SilkS")
		)
		(fp_line
			(start -0.094672 0.201008)
			(end -0.094672 -0.198992)
			(stroke
				(width 0.1)
				(type solid)
			)
			(layer "F.SilkS")
		)
		(fp_line
			(start 0.105328 0.201008)
			(end -0.094672 0.001008)
			(stroke
				(width 0.1)
				(type solid)
			)
			(layer "F.SilkS")
		)
		(fp_line
			(start 0.105328 0.201008)
			(end 0.105328 -0.198992)
			(stroke
				(width 0.1)
				(type solid)
			)
			(layer "F.SilkS")
		)
		(fp_line
			(start -0.094672 0.001008)
			(end -0.24 0.001008)
			(stroke
				(width 0.1)
				(type solid)
			)
			(layer "F.SilkS")
		)
		(fp_line
			(start -0.094672 0.001008)
			(end 0.105328 -0.198992)
			(stroke
				(width 0.1)
				(type solid)
			)
			(layer "F.SilkS")
		)
		(fp_line
			(start 0.105328 0.001008)
			(end 0.24 0.001)
			(stroke
				(width 0.1)
				(type solid)
			)
			(layer "F.SilkS")
		)
		(fp_line
			(start -1.18 -0.319)
			(end -1.18 0.321)
			(stroke
				(width 0.15)
				(type solid)
			)
			(layer "F.SilkS")
		)
		(fp_line
			(start 0.22 -0.35)
			(end -0.22 -0.35)
			(stroke
				(width 0.15)
				(type solid)
			)
			(layer "F.SilkS")
		)
		(fp_rect
			(start 1.25 0.65)
			(end -1.25 -0.65)
			(stroke
				(width 0.05)
				(type solid)
			)
			(fill none)
			(layer "F.CrtYd")
		)
		(fp_line
			(start -0.199 0.2)
			(end -0.199 0.1)
			(stroke
				(width 0.15)
				(type solid)
			)
			(layer "F.Fab")
		)
		(fp_line
			(start 0.201 0.2)
			(end 0.201 0)
			(stroke
				(width 0.15)
				(type solid)
			)
			(layer "F.Fab")
		)
		(fp_line
			(start -0.199 0)
			(end -0.597 0)
			(stroke
				(width 0.15)
				(type solid)
			)
			(layer "F.Fab")
		)
		(fp_line
			(start -0.101 0)
			(end 0.201 0.2)
			(stroke
				(width 0.15)
				(type solid)
			)
			(layer "F.Fab")
		)
		(fp_line
			(start 0.201 0)
			(end 0.201 -0.202)
			(stroke
				(width 0.15)
				(type solid)
			)
			(layer "F.Fab")
		)
		(fp_line
			(start 0.599 0)
			(end 0.201 0)
			(stroke
				(width 0.15)
				(type solid)
			)
			(layer "F.Fab")
		)
		(fp_line
			(start -0.199 -0.202)
			(end -0.199 0.1)
			(stroke
				(width 0.15)
				(type solid)
			)
			(layer "F.Fab")
		)
		(fp_line
			(start 0.201 -0.202)
			(end -0.101 0)
			(stroke
				(width 0.15)
				(type solid)
			)
			(layer "F.Fab")
		)
		(fp_rect
			(start 0.848 0.4)
			(end -0.85 -0.402)
			(stroke
				(width 0.15)
				(type solid)
			)
			(fill none)
			(layer "F.Fab")
		)
		(fp_text user "License: Apache-2.0"
			(at -1.4224 3.599 90)
			(layer "F.Fab")
			(hide yes)
			(effects
				(font
					(size 0.7 0.7)
					(thickness 0.15)
				)
				(justify right bottom)
			)
		)
		(fp_text user "${REFERENCE}"
			(at -1.4224 5.999 90)
			(layer "F.Fab")
			(hide yes)
			(effects
				(font
					(size 0.7 0.7)
					(thickness 0.15)
				)
				(justify right bottom)
			)
		)
		(fp_text user "Author: Antmicro"
			(at -1.4224 4.799 90)
			(layer "F.Fab")
			(hide yes)
			(effects
				(font
					(size 0.7 0.7)
					(thickness 0.15)
				)
				(justify right bottom)
			)
		)
		(pad "1" smd roundrect
			(at -0.7 0 90)
			(size 0.8 1)
			(layers "F.Cu" "F.Paste" "F.Mask")
			(roundrect_rratio 0.2)
			(net 70 "Net-(D6-C)")
			(pinfunction "C")
			(pintype "passive")
		)
		(pad "2" smd roundrect
			(at 0.7 0 90)
			(size 0.8 1)
			(layers "F.Cu" "F.Paste" "F.Mask")
			(roundrect_rratio 0.2)
			(net 71 "Net-(D6-A)")
			(pinfunction "A")
			(pintype "passive")
		)
	)
	(footprint "antmicro-footprints:R_0402_1005Metric"
		(layer "F.Cu")
		(at 161.6 85.598 180)
		(descr "Resistor SMD 0402")
		(tags "resistor SMD 0402")
		(property "Reference" "R16"
			(at 0.95 -0.39 0)
			(layer "F.SilkS")
			(effects
				(font
					(size 0.7 0.7)
					(thickness 0.15)
				)
				(justify right bottom)
			)
		)
		(property "Value" "R_5k1_0402"
			(at -1.011843 1.772047 0)
			(layer "F.Fab")
			(effects
				(font
					(size 0.7 0.7)
					(thickness 0.15)
				)
				(justify right bottom)
			)
		)
		(property "Footprint" "antmicro-footprints:R_0402_1005Metric"
			(at 0 0 180)
			(layer "F.Fab")
			(hide yes)
			(effects
				(font
					(size 1.27 1.27)
					(thickness 0.15)
				)
			)
		)
		(property "Datasheet" "https://www.bourns.com/docs/product-datasheets/cr.pdf"
			(at 0 0 180)
			(layer "F.Fab")
			(hide yes)
			(effects
				(font
					(size 1.27 1.27)
					(thickness 0.15)
				)
			)
		)
		(property "Author" "Antmicro"
			(at 323.2 171.196 0)
			(layer "F.Fab")
			(hide yes)
			(effects
				(font
					(size 1 1)
					(thickness 0.15)
				)
			)
		)
		(property "License" "Apache-2.0"
			(at 323.2 171.196 0)
			(layer "F.Fab")
			(hide yes)
			(effects
				(font
					(size 1 1)
					(thickness 0.15)
				)
			)
		)
		(property "MPN" "CR0402-FX-5101GLF"
			(at 323.2 171.196 0)
			(layer "F.Fab")
			(hide yes)
			(effects
				(font
					(size 1 1)
					(thickness 0.15)
				)
			)
		)
		(property "Manufacturer" "Bourns"
			(at 323.2 171.196 0)
			(layer "F.Fab")
			(hide yes)
			(effects
				(font
					(size 1 1)
					(thickness 0.15)
				)
			)
		)
		(property "Tolerance" "1%"
			(at 323.2 171.196 0)
			(layer "F.Fab")
			(hide yes)
			(effects
				(font
					(size 1 1)
					(thickness 0.15)
				)
			)
		)
		(property "Val" "5k1"
			(at 323.2 171.196 0)
			(layer "F.Fab")
			(hide yes)
			(effects
				(font
					(size 1 1)
					(thickness 0.15)
				)
			)
		)
		(sheetname "GMSL Connector")
		(sheetfile "GMSL.kicad_sch")
		(attr smd)
		(fp_rect
			(start -0.925 -0.47)
			(end 0.925 0.47)
			(stroke
				(width 0.05)
				(type default)
			)
			(fill none)
			(layer "F.CrtYd")
		)
		(fp_rect
			(start -0.5 -0.25)
			(end 0.5 0.25)
			(stroke
				(width 0.15)
				(type solid)
			)
			(fill none)
			(layer "F.Fab")
		)
		(fp_text user "${REFERENCE}"
			(at -0.95 3.168 0)
			(layer "F.Fab")
			(hide yes)
			(effects
				(font
					(size 0.7 0.7)
					(thickness 0.15)
				)
				(justify right bottom)
			)
		)
		(fp_text user "Author: Antmicro"
			(at -0.95 4.169 0)
			(layer "F.Fab")
			(hide yes)
			(effects
				(font
					(size 0.7 0.7)
					(thickness 0.15)
				)
				(justify right bottom)
			)
		)
		(fp_text user "License: Apache-2.0"
			(at -0.95 5.169 0)
			(layer "F.Fab")
			(hide yes)
			(effects
				(font
					(size 0.7 0.7)
					(thickness 0.15)
				)
				(justify right bottom)
			)
		)
		(pad "1" smd roundrect
			(at -0.48 0 180)
			(size 0.59 0.64)
			(layers "F.Cu" "F.Paste" "F.Mask")
			(roundrect_rratio 0.25)
			(net 2 "+12V")
			(pintype "passive")
		)
		(pad "2" smd roundrect
			(at 0.48 0 180)
			(size 0.59 0.64)
			(layers "F.Cu" "F.Paste" "F.Mask")
			(roundrect_rratio 0.25)
			(net 58 "Net-(L3-Pad2)")
			(pintype "passive")
		)
	)
	(footprint "antmicro-footprints:C_0402_1005Metric"
		(layer "B.Cu")
		(at 150.17 101.44 45)
		(descr "Capacitor SMD 0402")
		(tags "capacitor SMD 0402")
		(property "Reference" "C28"
			(at -3.563818 0.381838 45)
			(layer "B.SilkS")
			(effects
				(font
					(size 0.7 0.7)
					(thickness 0.15)
				)
				(justify right bottom mirror)
			)
		)
		(property "Value" "C_10n_0402"
			(at -0.676445 -2.119857 45)
			(layer "B.Fab")
			(effects
				(font
					(size 0.7 0.7)
					(thickness 0.15)
				)
				(justify right bottom mirror)
			)
		)
		(property "Footprint" "antmicro-footprints:C_0402_1005Metric"
			(at 0 0 45)
			(layer "F.Fab")
			(hide yes)
			(effects
				(font
					(size 1.27 1.27)
					(thickness 0.15)
				)
			)
		)
		(property "Datasheet" "https://www.murata.com/products/productdetail?partno=GRM155R71H103KA88%23"
			(at 0 0 45)
			(layer "F.Fab")
			(hide yes)
			(effects
				(font
					(size 1.27 1.27)
					(thickness 0.15)
				)
			)
		)
		(property "Author" "Antmicro"
			(at 115.712686 -76.475137 0)
			(layer "B.Fab")
			(hide yes)
			(effects
				(font
					(size 1 1)
					(thickness 0.15)
				)
				(justify mirror)
			)
		)
		(property "Dielectric" "X7R"
			(at 115.712686 -76.475137 0)
			(layer "B.Fab")
			(hide yes)
			(effects
				(font
					(size 1 1)
					(thickness 0.15)
				)
				(justify mirror)
			)
		)
		(property "License" "Apache-2.0"
			(at 115.712686 -76.475137 0)
			(layer "B.Fab")
			(hide yes)
			(effects
				(font
					(size 1 1)
					(thickness 0.15)
				)
				(justify mirror)
			)
		)
		(property "MPN" "GRM155R71H103KA88D"
			(at 115.712686 -76.475137 0)
			(layer "B.Fab")
			(hide yes)
			(effects
				(font
					(size 1 1)
					(thickness 0.15)
				)
				(justify mirror)
			)
		)
		(property "Manufacturer" "Murata"
			(at 115.712686 -76.475137 0)
			(layer "B.Fab")
			(hide yes)
			(effects
				(font
					(size 1 1)
					(thickness 0.15)
				)
				(justify mirror)
			)
		)
		(property "Val" "10n"
			(at 115.712686 -76.475137 0)
			(layer "B.Fab")
			(hide yes)
			(effects
				(font
					(size 1 1)
					(thickness 0.15)
				)
				(justify mirror)
			)
		)
		(property "Voltage" "50V"
			(at 115.712686 -76.475137 0)
			(layer "B.Fab")
			(hide yes)
			(effects
				(font
					(size 1 1)
					(thickness 0.15)
				)
				(justify mirror)
			)
		)
		(sheetname "Serializer")
		(sheetfile "serializer.kicad_sch")
		(attr smd)
		(fp_poly
			(pts
				(xy -0.925 0.47) (xy 0.925 0.47) (xy 0.925 -0.47) (xy -0.925 -0.47)
			)
			(stroke
				(width 0.05)
				(type default)
			)
			(fill none)
			(layer "B.CrtYd")
		)
		(fp_line
			(start -0.494 -0.248)
			(end 0.504 -0.248)
			(stroke
				(width 0.15)
				(type solid)
			)
			(layer "B.Fab")
		)
		(fp_line
			(start -0.494 0.25)
			(end -0.494 -0.248)
			(stroke
				(width 0.15)
				(type solid)
			)
			(layer "B.Fab")
		)
		(fp_line
			(start 0.504 -0.248)
			(end 0.504 0.25)
			(stroke
				(width 0.15)
				(type solid)
			)
			(layer "B.Fab")
		)
		(fp_line
			(start 0.504 0.25)
			(end -0.494 0.25)
			(stroke
				(width 0.15)
				(type solid)
			)
			(layer "B.Fab")
		)
		(fp_text user "${REFERENCE}"
			(at -0.939 -4.599 45)
			(layer "B.Fab")
			(hide yes)
			(effects
				(font
					(size 0.7 0.7)
					(thickness 0.15)
				)
				(justify right bottom mirror)
			)
		)
		(fp_text user "License: Apache-2.0"
			(at -0.939 -5.799 45)
			(layer "B.Fab")
			(hide yes)
			(effects
				(font
					(size 0.7 0.7)
					(thickness 0.15)
				)
				(justify right bottom mirror)
			)
		)
		(fp_text user "Author: Antmicro"
			(at -0.939 -3.399 45)
			(layer "B.Fab")
			(hide yes)
			(effects
				(font
					(size 0.7 0.7)
					(thickness 0.15)
				)
				(justify right bottom mirror)
			)
		)
		(pad "1" smd roundrect
			(at -0.48 0 45)
			(size 0.59 0.64)
			(layers "B.Cu" "B.Paste" "B.Mask")
			(roundrect_rratio 0.25)
			(net 1 "GND")
			(pintype "passive")
		)
		(pad "2" smd roundrect
			(at 0.48 0 45)
			(size 0.59 0.64)
			(layers "B.Cu" "B.Paste" "B.Mask")
			(roundrect_rratio 0.25)
			(net 11 "+1V8")
			(pintype "passive")
		)
	)
	(footprint "antmicro-footprints:C_0402_1005Metric"
		(layer "B.Cu")
		(at 148.090036 99.360037 45)
		(descr "Capacitor SMD 0402")
		(tags "capacitor SMD 0402")
		(property "Reference" "C24"
			(at -3.570889 0.431284 45)
			(layer "B.SilkS")
			(effects
				(font
					(size 0.7 0.7)
					(thickness 0.15)
				)
				(justify right bottom mirror)
			)
		)
		(property "Value" "C_100n_0402"
			(at -1.022927 -2.155213 45)
			(layer "B.Fab")
			(effects
				(font
					(size 0.7 0.7)
					(thickness 0.15)
				)
				(justify right bottom mirror)
			)
		)
		(property "Footprint" "antmicro-footprints:C_0402_1005Metric"
			(at 0 0 45)
			(layer "F.Fab")
			(hide yes)
			(effects
				(font
					(size 1.27 1.27)
					(thickness 0.15)
				)
			)
		)
		(property "Datasheet" "https://www.murata.com/products/productdetail?partno=GRM155R61H104KE14%23"
			(at 0 0 45)
			(layer "F.Fab")
			(hide yes)
			(effects
				(font
					(size 1.27 1.27)
					(thickness 0.15)
				)
			)
		)
		(property "Author" "Antmicro"
			(at 113.632724 -75.613588 0)
			(layer "B.Fab")
			(hide yes)
			(effects
				(font
					(size 1 1)
					(thickness 0.15)
				)
				(justify mirror)
			)
		)
		(property "Dielectric" "X5R"
			(at 113.632724 -75.613588 0)
			(layer "B.Fab")
			(hide yes)
			(effects
				(font
					(size 1 1)
					(thickness 0.15)
				)
				(justify mirror)
			)
		)
		(property "License" "Apache-2.0"
			(at 113.632724 -75.613588 0)
			(layer "B.Fab")
			(hide yes)
			(effects
				(font
					(size 1 1)
					(thickness 0.15)
				)
				(justify mirror)
			)
		)
		(property "MPN" "GRM155R61H104KE14D"
			(at 113.632724 -75.613588 0)
			(layer "B.Fab")
			(hide yes)
			(effects
				(font
					(size 1 1)
					(thickness 0.15)
				)
				(justify mirror)
			)
		)
		(property "Manufacturer" "Murata"
			(at 113.632724 -75.613588 0)
			(layer "B.Fab")
			(hide yes)
			(effects
				(font
					(size 1 1)
					(thickness 0.15)
				)
				(justify mirror)
			)
		)
		(property "Val" "100n"
			(at 113.632724 -75.613588 0)
			(layer "B.Fab")
			(hide yes)
			(effects
				(font
					(size 1 1)
					(thickness 0.15)
				)
				(justify mirror)
			)
		)
		(property "Voltage" "50V"
			(at 113.632724 -75.613588 0)
			(layer "B.Fab")
			(hide yes)
			(effects
				(font
					(size 1 1)
					(thickness 0.15)
				)
				(justify mirror)
			)
		)
		(sheetname "Serializer")
		(sheetfile "serializer.kicad_sch")
		(attr smd)
		(fp_poly
			(pts
				(xy -0.925 0.47) (xy 0.925 0.47) (xy 0.925 -0.47) (xy -0.925 -0.47)
			)
			(stroke
				(width 0.05)
				(type default)
			)
			(fill none)
			(layer "B.CrtYd")
		)
		(fp_line
			(start -0.494 -0.248)
			(end 0.504 -0.248)
			(stroke
				(width 0.15)
				(type solid)
			)
			(layer "B.Fab")
		)
		(fp_line
			(start -0.494 0.25)
			(end -0.494 -0.248)
			(stroke
				(width 0.15)
				(type solid)
			)
			(layer "B.Fab")
		)
		(fp_line
			(start 0.504 -0.248)
			(end 0.504 0.25)
			(stroke
				(width 0.15)
				(type solid)
			)
			(layer "B.Fab")
		)
		(fp_line
			(start 0.504 0.25)
			(end -0.494 0.25)
			(stroke
				(width 0.15)
				(type solid)
			)
			(layer "B.Fab")
		)
		(fp_text user "Author: Antmicro"
			(at -0.939 -3.399 45)
			(layer "B.Fab")
			(hide yes)
			(effects
				(font
					(size 0.7 0.7)
					(thickness 0.15)
				)
				(justify right bottom mirror)
			)
		)
		(fp_text user "License: Apache-2.0"
			(at -0.939 -5.799 45)
			(layer "B.Fab")
			(hide yes)
			(effects
				(font
					(size 0.7 0.7)
					(thickness 0.15)
				)
				(justify right bottom mirror)
			)
		)
		(fp_text user "${REFERENCE}"
			(at -0.939 -4.599 45)
			(layer "B.Fab")
			(hide yes)
			(effects
				(font
					(size 0.7 0.7)
					(thickness 0.15)
				)
				(justify right bottom mirror)
			)
		)
		(pad "1" smd roundrect
			(at -0.48 0 45)
			(size 0.59 0.64)
			(layers "B.Cu" "B.Paste" "B.Mask")
			(roundrect_rratio 0.25)
			(net 1 "GND")
			(pintype "passive")
		)
		(pad "2" smd roundrect
			(at 0.48 0 45)
			(size 0.59 0.64)
			(layers "B.Cu" "B.Paste" "B.Mask")
			(roundrect_rratio 0.25)
			(net 15 "Net-(U6-CAP_VDD)")
			(pintype "passive")
		)
	)
)
